(kicad_pcb
	(version 20260206)
	(generator "pcbnew")
	(generator_version "10.0")
	(general
		(thickness 1.6)
		(legacy_teardrops no)
	)
	(paper "A4")
	(title_block
		(title "01162023_DA0F0TEBIF0_F0T_Expander_BD_F_brd_V02_OCP.brd")
		(comment 1 "Grand Teton / footprints 1029-1036 of 9728")
	)
	(layers
		(0 "F.Cu" signal "TOP")
		(4 "In1.Cu" signal "GND")
		(6 "In2.Cu" signal "VCC")
		(8 "In3.Cu" signal "VCC1")
		(10 "In4.Cu" signal "GND1")
		(12 "In5.Cu" signal "IN1")
		(14 "In6.Cu" signal "GND2")
		(16 "In7.Cu" signal "IN2")
		(18 "In8.Cu" signal "GND3")
		(20 "In9.Cu" signal "IN3")
		(22 "In10.Cu" signal "GND4")
		(24 "In11.Cu" signal "IN4")
		(26 "In12.Cu" signal "GND5")
		(28 "In13.Cu" signal "IN5")
		(30 "In14.Cu" signal "GND6")
		(32 "In15.Cu" signal "IN6")
		(34 "In16.Cu" signal "GND7")
		(2 "B.Cu" signal "BOTTOM")
		(9 "F.Adhes" user "F.Adhesive")
		(11 "B.Adhes" user "B.Adhesive")
		(13 "F.Paste" user "Package Geometry/Pastemask Top")
		(15 "B.Paste" user "Package Geometry/Pastemask Bottom")
		(5 "F.SilkS" user "Ref Des/Silkscreen Top")
		(7 "B.SilkS" user "Ref Des/Silkscreen Bottom")
		(1 "F.Mask" user "Board Geometry/Soldermask Top")
		(3 "B.Mask" user "Board Geometry/Soldermask Bottom")
		(17 "Dwgs.User" user "User.Drawings")
		(19 "Cmts.User" user "User.Comments")
		(21 "Eco1.User" user "User.Eco1")
		(23 "Eco2.User" user "User.Eco2")
		(25 "Edge.Cuts" user "Board Geometry/Outline")
		(27 "Margin" user)
		(31 "F.CrtYd" user "Package Geometry/Place Bound Top")
		(29 "B.CrtYd" user "Package Geometry/Place Bound Bottom")
		(35 "F.Fab" user "Ref Des/Assembly Top")
		(33 "B.Fab" user "Ref Des/Assembly Bottom")
	)
	(footprint ""
		(layer "F.Cu")
		(at 427.614842 -79.58201 90)
		(property "Reference" "R406"
			(at 0 0 90)
			(layer "F.SilkS")
			(hide yes)
			(effects
				(font
					(size 1.27 1.27)
				)
			)
		)
		(property "Value" ""
			(at 0 0 90)
			(layer "F.Fab")
			(effects
				(font
					(size 1.27 1.27)
				)
			)
		)
		(duplicate_pad_numbers_are_jumpers no)
		(fp_line
			(start 0.7874 -0.4064)
			(end 0.7874 0.4064)
			(stroke
				(width 0.1524)
				(type default)
			)
			(layer "F.SilkS")
		)
		(fp_line
			(start -0.7874 -0.4064)
			(end 0.7874 -0.4064)
			(stroke
				(width 0.1524)
				(type default)
			)
			(layer "F.SilkS")
		)
		(fp_line
			(start 0.7874 0.4064)
			(end -0.7874 0.4064)
			(stroke
				(width 0.1524)
				(type default)
			)
			(layer "F.SilkS")
		)
		(fp_line
			(start -0.7874 0.4064)
			(end -0.7874 -0.4064)
			(stroke
				(width 0.1524)
				(type default)
			)
			(layer "F.SilkS")
		)
		(fp_line
			(start -0.12065 -0.305054)
			(end -0.12065 -0.2794)
			(stroke
				(width 0.1)
				(type default)
			)
			(layer "F.Fab")
		)
		(fp_line
			(start -0.67945 -0.305054)
			(end -0.12065 -0.305054)
			(stroke
				(width 0.1)
				(type default)
			)
			(layer "F.Fab")
		)
		(fp_line
			(start 0.67945 -0.3048)
			(end 0.67945 0.3048)
			(stroke
				(width 0.1)
				(type default)
			)
			(layer "F.Fab")
		)
		(fp_line
			(start 0.12065 -0.3048)
			(end 0.67945 -0.3048)
			(stroke
				(width 0.1)
				(type default)
			)
			(layer "F.Fab")
		)
		(fp_line
			(start 0.12065 -0.2794)
			(end 0.12065 -0.3048)
			(stroke
				(width 0.1)
				(type default)
			)
			(layer "F.Fab")
		)
		(fp_line
			(start -0.12065 -0.2794)
			(end 0.12065 -0.2794)
			(stroke
				(width 0.1)
				(type default)
			)
			(layer "F.Fab")
		)
		(fp_line
			(start 0.120396 0.2794)
			(end -0.12065 0.2794)
			(stroke
				(width 0.1)
				(type default)
			)
			(layer "F.Fab")
		)
		(fp_line
			(start -0.12065 0.2794)
			(end -0.12065 0.3048)
			(stroke
				(width 0.1)
				(type default)
			)
			(layer "F.Fab")
		)
		(fp_line
			(start 0.67945 0.3048)
			(end 0.120396 0.3048)
			(stroke
				(width 0.1)
				(type default)
			)
			(layer "F.Fab")
		)
		(fp_line
			(start 0.120396 0.3048)
			(end 0.120396 0.2794)
			(stroke
				(width 0.1)
				(type default)
			)
			(layer "F.Fab")
		)
		(fp_line
			(start -0.12065 0.3048)
			(end -0.67945 0.3048)
			(stroke
				(width 0.1)
				(type default)
			)
			(layer "F.Fab")
		)
		(fp_line
			(start -0.67945 0.3048)
			(end -0.67945 -0.305054)
			(stroke
				(width 0.1)
				(type default)
			)
			(layer "F.Fab")
		)
		(pad "1" smd circle
			(at -0.40005 0 90)
			(size 0 0)
			(layers "F.Cu" "F.Mask" "F.Paste")
			(net "P3V3_NIC7")
		)
		(pad "2" smd circle
			(at 0.40005 0 90)
			(size 0 0)
			(layers "F.Cu" "F.Mask" "F.Paste")
			(net "HP_NIC7_PWRGD")
		)
	)
	(footprint ""
		(layer "F.Cu")
		(at 197.983602 -61.487812 180)
		(property "Reference" "R5985"
			(at 0 0 180)
			(layer "F.SilkS")
			(hide yes)
			(effects
				(font
					(size 1.27 1.27)
				)
			)
		)
		(property "Value" ""
			(at 0 0 180)
			(layer "F.Fab")
			(effects
				(font
					(size 1.27 1.27)
				)
			)
		)
		(duplicate_pad_numbers_are_jumpers no)
		(fp_line
			(start 0.7874 0.4064)
			(end -0.7874 0.4064)
			(stroke
				(width 0.1524)
				(type default)
			)
			(layer "F.SilkS")
		)
		(fp_line
			(start 0.7874 -0.4064)
			(end 0.7874 0.4064)
			(stroke
				(width 0.1524)
				(type default)
			)
			(layer "F.SilkS")
		)
		(fp_line
			(start -0.7874 0.4064)
			(end -0.7874 -0.4064)
			(stroke
				(width 0.1524)
				(type default)
			)
			(layer "F.SilkS")
		)
		(fp_line
			(start -0.7874 -0.4064)
			(end 0.7874 -0.4064)
			(stroke
				(width 0.1524)
				(type default)
			)
			(layer "F.SilkS")
		)
		(fp_line
			(start 0.67945 0.3048)
			(end 0.120396 0.3048)
			(stroke
				(width 0.1)
				(type default)
			)
			(layer "F.Fab")
		)
		(fp_line
			(start 0.67945 -0.3048)
			(end 0.67945 0.3048)
			(stroke
				(width 0.1)
				(type default)
			)
			(layer "F.Fab")
		)
		(fp_line
			(start 0.12065 -0.2794)
			(end 0.12065 -0.3048)
			(stroke
				(width 0.1)
				(type default)
			)
			(layer "F.Fab")
		)
		(fp_line
			(start 0.12065 -0.3048)
			(end 0.67945 -0.3048)
			(stroke
				(width 0.1)
				(type default)
			)
			(layer "F.Fab")
		)
		(fp_line
			(start 0.120396 0.3048)
			(end 0.120396 0.2794)
			(stroke
				(width 0.1)
				(type default)
			)
			(layer "F.Fab")
		)
		(fp_line
			(start 0.120396 0.2794)
			(end -0.12065 0.2794)
			(stroke
				(width 0.1)
				(type default)
			)
			(layer "F.Fab")
		)
		(fp_line
			(start -0.12065 0.3048)
			(end -0.67945 0.3048)
			(stroke
				(width 0.1)
				(type default)
			)
			(layer "F.Fab")
		)
		(fp_line
			(start -0.12065 0.2794)
			(end -0.12065 0.3048)
			(stroke
				(width 0.1)
				(type default)
			)
			(layer "F.Fab")
		)
		(fp_line
			(start -0.12065 -0.2794)
			(end 0.12065 -0.2794)
			(stroke
				(width 0.1)
				(type default)
			)
			(layer "F.Fab")
		)
		(fp_line
			(start -0.12065 -0.305054)
			(end -0.12065 -0.2794)
			(stroke
				(width 0.1)
				(type default)
			)
			(layer "F.Fab")
		)
		(fp_line
			(start -0.67945 0.3048)
			(end -0.67945 -0.305054)
			(stroke
				(width 0.1)
				(type default)
			)
			(layer "F.Fab")
		)
		(fp_line
			(start -0.67945 -0.305054)
			(end -0.12065 -0.305054)
			(stroke
				(width 0.1)
				(type default)
			)
			(layer "F.Fab")
		)
		(pad "1" smd circle
			(at -0.40005 0 180)
			(size 0 0)
			(layers "F.Cu" "F.Mask" "F.Paste")
			(net "PWRGD_P12V_SSD7_D")
		)
		(pad "2" smd circle
			(at 0.40005 0 180)
			(size 0 0)
			(layers "F.Cu" "F.Mask" "F.Paste")
			(net "PWRGD_P12V_SSD7_R")
		)
	)
	(footprint ""
		(layer "F.Cu")
		(at 90.241882 -343.952322 90)
		(property "Reference" "C102"
			(at 0 0 90)
			(layer "F.SilkS")
			(hide yes)
			(effects
				(font
					(size 1.27 1.27)
				)
			)
		)
		(property "Value" ""
			(at 0 0 90)
			(layer "F.Fab")
			(effects
				(font
					(size 1.27 1.27)
				)
			)
		)
		(duplicate_pad_numbers_are_jumpers no)
		(fp_line
			(start 0.299974 -0.150114)
			(end 0.299974 0.150114)
			(stroke
				(width 0.1)
				(type default)
			)
			(layer "F.Fab")
		)
		(fp_line
			(start -0.299974 -0.150114)
			(end 0.299974 -0.150114)
			(stroke
				(width 0.1)
				(type default)
			)
			(layer "F.Fab")
		)
		(fp_line
			(start 0.299974 0.150114)
			(end -0.299974 0.150114)
			(stroke
				(width 0.1)
				(type default)
			)
			(layer "F.Fab")
		)
		(fp_line
			(start -0.299974 0.150114)
			(end -0.299974 -0.150114)
			(stroke
				(width 0.1)
				(type default)
			)
			(layer "F.Fab")
		)
		(pad "1" smd rect
			(at -0.2667 0 90)
			(size 0.3048 0.381)
			(layers "F.Cu" "F.Mask" "F.Paste")
			(net "P5E_PEX0_STN5_TX_DN<93>")
		)
		(pad "2" smd rect
			(at 0.2667 0 90)
			(size 0.3048 0.381)
			(layers "F.Cu" "F.Mask" "F.Paste")
			(net "P5E_PEX0_STN5_TX_C_DN<93>")
		)
	)
	(footprint ""
		(layer "F.Cu")
		(at 362.351574 -241.697002 180)
		(property "Reference" "R6406"
			(at 0 0 180)
			(layer "F.SilkS")
			(hide yes)
			(effects
				(font
					(size 1.27 1.27)
				)
			)
		)
		(property "Value" ""
			(at 0 0 180)
			(layer "F.Fab")
			(effects
				(font
					(size 1.27 1.27)
				)
			)
		)
		(duplicate_pad_numbers_are_jumpers no)
		(fp_line
			(start 0.7874 0.4064)
			(end -0.7874 0.4064)
			(stroke
				(width 0.1524)
				(type default)
			)
			(layer "F.SilkS")
		)
		(fp_line
			(start 0.7874 -0.4064)
			(end 0.7874 0.4064)
			(stroke
				(width 0.1524)
				(type default)
			)
			(layer "F.SilkS")
		)
		(fp_line
			(start -0.7874 0.4064)
			(end -0.7874 -0.4064)
			(stroke
				(width 0.1524)
				(type default)
			)
			(layer "F.SilkS")
		)
		(fp_line
			(start -0.7874 -0.4064)
			(end 0.7874 -0.4064)
			(stroke
				(width 0.1524)
				(type default)
			)
			(layer "F.SilkS")
		)
		(fp_line
			(start 0.67945 0.3048)
			(end 0.120396 0.3048)
			(stroke
				(width 0.1)
				(type default)
			)
			(layer "F.Fab")
		)
		(fp_line
			(start 0.67945 -0.3048)
			(end 0.67945 0.3048)
			(stroke
				(width 0.1)
				(type default)
			)
			(layer "F.Fab")
		)
		(fp_line
			(start 0.12065 -0.2794)
			(end 0.12065 -0.3048)
			(stroke
				(width 0.1)
				(type default)
			)
			(layer "F.Fab")
		)
		(fp_line
			(start 0.12065 -0.3048)
			(end 0.67945 -0.3048)
			(stroke
				(width 0.1)
				(type default)
			)
			(layer "F.Fab")
		)
		(fp_line
			(start 0.120396 0.3048)
			(end 0.120396 0.2794)
			(stroke
				(width 0.1)
				(type default)
			)
			(layer "F.Fab")
		)
		(fp_line
			(start 0.120396 0.2794)
			(end -0.12065 0.2794)
			(stroke
				(width 0.1)
				(type default)
			)
			(layer "F.Fab")
		)
		(fp_line
			(start -0.12065 0.3048)
			(end -0.67945 0.3048)
			(stroke
				(width 0.1)
				(type default)
			)
			(layer "F.Fab")
		)
		(fp_line
			(start -0.12065 0.2794)
			(end -0.12065 0.3048)
			(stroke
				(width 0.1)
				(type default)
			)
			(layer "F.Fab")
		)
		(fp_line
			(start -0.12065 -0.2794)
			(end 0.12065 -0.2794)
			(stroke
				(width 0.1)
				(type default)
			)
			(layer "F.Fab")
		)
		(fp_line
			(start -0.12065 -0.305054)
			(end -0.12065 -0.2794)
			(stroke
				(width 0.1)
				(type default)
			)
			(layer "F.Fab")
		)
		(fp_line
			(start -0.67945 0.3048)
			(end -0.67945 -0.305054)
			(stroke
				(width 0.1)
				(type default)
			)
			(layer "F.Fab")
		)
		(fp_line
			(start -0.67945 -0.305054)
			(end -0.12065 -0.305054)
			(stroke
				(width 0.1)
				(type default)
			)
			(layer "F.Fab")
		)
		(pad "1" smd circle
			(at -0.40005 0 180)
			(size 0 0)
			(layers "F.Cu" "F.Mask" "F.Paste")
			(net "PWRGD_P12V_AUX_R1")
		)
		(pad "2" smd circle
			(at 0.40005 0 180)
			(size 0 0)
			(layers "F.Cu" "F.Mask" "F.Paste")
			(net "PWRGD_P12V_AUX_R")
		)
	)
	(footprint ""
		(layer "F.Cu")
		(at 364.947454 -397.425672 90)
		(property "Reference" "R6705"
			(at 0 0 90)
			(layer "F.SilkS")
			(hide yes)
			(effects
				(font
					(size 1.27 1.27)
				)
			)
		)
		(property "Value" ""
			(at 0 0 90)
			(layer "F.Fab")
			(effects
				(font
					(size 1.27 1.27)
				)
			)
		)
		(duplicate_pad_numbers_are_jumpers no)
		(fp_line
			(start 0.7874 -0.4064)
			(end 0.7874 0.4064)
			(stroke
				(width 0.1524)
				(type default)
			)
			(layer "F.SilkS")
		)
		(fp_line
			(start -0.7874 -0.4064)
			(end 0.7874 -0.4064)
			(stroke
				(width 0.1524)
				(type default)
			)
			(layer "F.SilkS")
		)
		(fp_line
			(start 0.7874 0.4064)
			(end -0.7874 0.4064)
			(stroke
				(width 0.1524)
				(type default)
			)
			(layer "F.SilkS")
		)
		(fp_line
			(start -0.7874 0.4064)
			(end -0.7874 -0.4064)
			(stroke
				(width 0.1524)
				(type default)
			)
			(layer "F.SilkS")
		)
		(fp_line
			(start -0.12065 -0.305054)
			(end -0.12065 -0.2794)
			(stroke
				(width 0.1)
				(type default)
			)
			(layer "F.Fab")
		)
		(fp_line
			(start -0.67945 -0.305054)
			(end -0.12065 -0.305054)
			(stroke
				(width 0.1)
				(type default)
			)
			(layer "F.Fab")
		)
		(fp_line
			(start 0.67945 -0.3048)
			(end 0.67945 0.3048)
			(stroke
				(width 0.1)
				(type default)
			)
			(layer "F.Fab")
		)
		(fp_line
			(start 0.12065 -0.3048)
			(end 0.67945 -0.3048)
			(stroke
				(width 0.1)
				(type default)
			)
			(layer "F.Fab")
		)
		(fp_line
			(start 0.12065 -0.2794)
			(end 0.12065 -0.3048)
			(stroke
				(width 0.1)
				(type default)
			)
			(layer "F.Fab")
		)
		(fp_line
			(start -0.12065 -0.2794)
			(end 0.12065 -0.2794)
			(stroke
				(width 0.1)
				(type default)
			)
			(layer "F.Fab")
		)
		(fp_line
			(start 0.120396 0.2794)
			(end -0.12065 0.2794)
			(stroke
				(width 0.1)
				(type default)
			)
			(layer "F.Fab")
		)
		(fp_line
			(start -0.12065 0.2794)
			(end -0.12065 0.3048)
			(stroke
				(width 0.1)
				(type default)
			)
			(layer "F.Fab")
		)
		(fp_line
			(start 0.67945 0.3048)
			(end 0.120396 0.3048)
			(stroke
				(width 0.1)
				(type default)
			)
			(layer "F.Fab")
		)
		(fp_line
			(start 0.120396 0.3048)
			(end 0.120396 0.2794)
			(stroke
				(width 0.1)
				(type default)
			)
			(layer "F.Fab")
		)
		(fp_line
			(start -0.12065 0.3048)
			(end -0.67945 0.3048)
			(stroke
				(width 0.1)
				(type default)
			)
			(layer "F.Fab")
		)
		(fp_line
			(start -0.67945 0.3048)
			(end -0.67945 -0.305054)
			(stroke
				(width 0.1)
				(type default)
			)
			(layer "F.Fab")
		)
		(pad "1" smd circle
			(at -0.40005 0 90)
			(size 0 0)
			(layers "F.Cu" "F.Mask" "F.Paste")
			(net "MB_3V3IO_RSVD3")
		)
		(pad "2" smd circle
			(at 0.40005 0 90)
			(size 0 0)
			(layers "F.Cu" "F.Mask" "F.Paste")
			(net "GND")
		)
	)
	(footprint ""
		(layer "F.Cu")
		(at 36.638484 -111.895382)
		(property "Reference" "C49"
			(at 0 0 0)
			(layer "F.SilkS")
			(hide yes)
			(effects
				(font
					(size 1.27 1.27)
				)
			)
		)
		(property "Value" ""
			(at 0 0 0)
			(layer "F.Fab")
			(effects
				(font
					(size 1.27 1.27)
				)
			)
		)
		(duplicate_pad_numbers_are_jumpers no)
		(fp_line
			(start -0.299974 -0.150114)
			(end 0.299974 -0.150114)
			(stroke
				(width 0.1)
				(type default)
			)
			(layer "F.Fab")
		)
		(fp_line
			(start -0.299974 0.150114)
			(end -0.299974 -0.150114)
			(stroke
				(width 0.1)
				(type default)
			)
			(layer "F.Fab")
		)
		(fp_line
			(start 0.299974 -0.150114)
			(end 0.299974 0.150114)
			(stroke
				(width 0.1)
				(type default)
			)
			(layer "F.Fab")
		)
		(fp_line
			(start 0.299974 0.150114)
			(end -0.299974 0.150114)
			(stroke
				(width 0.1)
				(type default)
			)
			(layer "F.Fab")
		)
		(pad "1" smd rect
			(at -0.2667 0)
			(size 0.3048 0.381)
			(layers "F.Cu" "F.Mask" "F.Paste")
			(net "P5E_PEX0_STN1_TX_DN<23>")
		)
		(pad "2" smd rect
			(at 0.2667 0)
			(size 0.3048 0.381)
			(layers "F.Cu" "F.Mask" "F.Paste")
			(net "P5E_PEX0_STN1_TX_C_DN<23>")
		)
	)
	(footprint ""
		(layer "F.Cu")
		(at 301.992284 -28.225242 180)
		(property "Reference" "C510"
			(at 0 0 180)
			(layer "F.SilkS")
			(hide yes)
			(effects
				(font
					(size 1.27 1.27)
				)
			)
		)
		(property "Value" ""
			(at 0 0 180)
			(layer "F.Fab")
			(effects
				(font
					(size 1.27 1.27)
				)
			)
		)
		(duplicate_pad_numbers_are_jumpers no)
		(fp_line
			(start 0.299974 0.150114)
			(end -0.299974 0.150114)
			(stroke
				(width 0.1)
				(type default)
			)
			(layer "F.Fab")
		)
		(fp_line
			(start 0.299974 -0.150114)
			(end 0.299974 0.150114)
			(stroke
				(width 0.1)
				(type default)
			)
			(layer "F.Fab")
		)
		(fp_line
			(start -0.299974 0.150114)
			(end -0.299974 -0.150114)
			(stroke
				(width 0.1)
				(type default)
			)
			(layer "F.Fab")
		)
		(fp_line
			(start -0.299974 -0.150114)
			(end 0.299974 -0.150114)
			(stroke
				(width 0.1)
				(type default)
			)
			(layer "F.Fab")
		)
		(pad "1" smd rect
			(at -0.2667 0 180)
			(size 0.3048 0.381)
			(layers "F.Cu" "F.Mask" "F.Paste")
			(net "P5E_PEX2_STN2_TX_DN<36>")
		)
		(pad "2" smd rect
			(at 0.2667 0 180)
			(size 0.3048 0.381)
			(layers "F.Cu" "F.Mask" "F.Paste")
			(net "P5E_PEX2_STN2_TX_C_DN<36>")
		)
	)
	(footprint ""
		(layer "F.Cu")
		(at 183.923432 -356.22103 90)
		(property "Reference" "C2534"
			(at 0 0 90)
			(layer "F.SilkS")
			(hide yes)
			(effects
				(font
					(size 1.27 1.27)
				)
			)
		)
		(property "Value" ""
			(at 0 0 90)
			(layer "F.Fab")
			(effects
				(font
					(size 1.27 1.27)
				)
			)
		)
		(duplicate_pad_numbers_are_jumpers no)
		(fp_line
			(start 0.299974 -0.150114)
			(end 0.299974 0.150114)
			(stroke
				(width 0.1)
				(type default)
			)
			(layer "F.Fab")
		)
		(fp_line
			(start -0.299974 -0.150114)
			(end 0.299974 -0.150114)
			(stroke
				(width 0.1)
				(type default)
			)
			(layer "F.Fab")
		)
		(fp_line
			(start 0.299974 0.150114)
			(end -0.299974 0.150114)
			(stroke
				(width 0.1)
				(type default)
			)
			(layer "F.Fab")
		)
		(fp_line
			(start -0.299974 0.150114)
			(end -0.299974 -0.150114)
			(stroke
				(width 0.1)
				(type default)
			)
			(layer "F.Fab")
		)
		(pad "1" smd rect
			(at -0.2667 0 90)
			(size 0.3048 0.381)
			(layers "F.Cu" "F.Mask" "F.Paste")
			(net "P5E_PEX1_STN4_TX_DP<68>")
		)
		(pad "2" smd rect
			(at 0.2667 0 90)
			(size 0.3048 0.381)
			(layers "F.Cu" "F.Mask" "F.Paste")
			(net "P5E_PEX1_STN4_TX_C_DP<68>")
		)
	)
)
